# SCM (Grand Teton) — schematic netlist excerpt (pin names and nets, part order shuffled) for the footprints in the layout excerpt that follows; sources: Cadence DE-HDL packaged netlist, KiCad conversion of 12092022_DA0F0TMDCD0_F0T_Management_Board_D_brd_V3_OCP.brd

X12  TP_TDR_4P_FTS  TP_TDR_4P_DIP EMPTY  pkg TH  page 60
  S1  = TDR_DIFF_85_BOT_DN
  P1  = GND_P1
  P2  = GND_P1
  S2  = TDR_DIFF_85_BOT_DP

R173  Q_RES  22 1% CHIP  pkg 0402LF  page 13 : A = RMII_TXD1_R ; B = RMII_TXD1

(kicad_pcb
	(version 20260206)
	(generator "pcbnew")
	(generator_version "10.0")
	(general
		(thickness 1.6)
		(legacy_teardrops no)
	)
	(paper "A4")
	(title_block
		(title "12092022_DA0F0TMDCD0_F0T_Management_Board_D_brd_V3_OCP.brd")
		(comment 1 "Grand Teton / footprints 630-631 of 1440")
	)
	(layers
		(0 "F.Cu" signal "TOP")
		(4 "In1.Cu" signal "GND")
		(6 "In2.Cu" signal "IN1")
		(8 "In3.Cu" signal "GND1")
		(10 "In4.Cu" signal "IN2")
		(12 "In5.Cu" signal "VCC")
		(14 "In6.Cu" signal "VCC1")
		(16 "In7.Cu" signal "IN3")
		(18 "In8.Cu" signal "GND2")
		(20 "In9.Cu" signal "IN4")
		(22 "In10.Cu" signal "GND3")
		(2 "B.Cu" signal "BOTTOM")
		(9 "F.Adhes" user "F.Adhesive")
		(11 "B.Adhes" user "B.Adhesive")
		(13 "F.Paste" user "Package Geometry/Pastemask Top")
		(15 "B.Paste" user "Package Geometry/Pastemask Bottom")
		(5 "F.SilkS" user "Ref Des/Silkscreen Top")
		(7 "B.SilkS" user "Ref Des/Silkscreen Bottom")
		(1 "F.Mask" user "Board Geometry/Soldermask Top")
		(3 "B.Mask" user "Board Geometry/Soldermask Bottom")
		(17 "Dwgs.User" user "User.Drawings")
		(19 "Cmts.User" user "User.Comments")
		(21 "Eco1.User" user "User.Eco1")
		(23 "Eco2.User" user "User.Eco2")
		(25 "Edge.Cuts" user "Board Geometry/Outline")
		(27 "Margin" user)
		(31 "F.CrtYd" user "Package Geometry/Place Bound Top")
		(29 "B.CrtYd" user "Package Geometry/Place Bound Bottom")
		(35 "F.Fab" user "Ref Des/Assembly Top")
		(33 "B.Fab" user "Ref Des/Assembly Bottom")
	)
	(footprint ""
		(layer "F.Cu")
		(at 112.014 -24.384 90)
		(property "Reference" "X12"
			(at 0.3175 5.37337 90)
			(unlocked yes)
			(layer "F.SilkS")
			(effects
				(font
					(size 0.7874 0.5842)
					(thickness 0.1524)
				)
				(justify left)
			)
		)
		(property "Value" ""
			(at 0 0 90)
			(layer "F.Fab")
			(effects
				(font
					(size 1.27 1.27)
				)
			)
		)
		(property "Device Type" "TP_TDR_4P_FTS_TH-TP_TDR_4P_DIPA"
			(at 1.30175 1.27 180)
			(unlocked yes)
			(layer "F.Fab")
			(hide yes)
			(effects
				(font
					(size 0.635 0.4064)
					(thickness 0.1524)
				)
			)
		)
		(property "User Part Number" "N_A"
			(at 1.30175 1.27 180)
			(unlocked yes)
			(layer "Cmts.User")
			(hide yes)
			(effects
				(font
					(size 0.635 0.4064)
					(thickness 0.1524)
				)
			)
		)
		(duplicate_pad_numbers_are_jumpers no)
		(fp_line
			(start 2.54 -1.27)
			(end 0 -1.27)
			(stroke
				(width 0.1524)
				(type default)
			)
			(layer "F.SilkS")
		)
		(fp_line
			(start 0 -1.27)
			(end 0 -0.635)
			(stroke
				(width 0.1524)
				(type default)
			)
			(layer "F.SilkS")
		)
		(fp_line
			(start 2.54 -1.1303)
			(end 2.54 -1.27)
			(stroke
				(width 0.1524)
				(type default)
			)
			(layer "F.SilkS")
		)
		(fp_line
			(start 0 0.635)
			(end 0 1.905)
			(stroke
				(width 0.1524)
				(type default)
			)
			(layer "F.SilkS")
		)
		(fp_line
			(start 2.54 1.4097)
			(end 2.54 1.1303)
			(stroke
				(width 0.1524)
				(type default)
			)
			(layer "F.SilkS")
		)
		(fp_line
			(start 0 3.175)
			(end 0 3.81)
			(stroke
				(width 0.1524)
				(type default)
			)
			(layer "F.SilkS")
		)
		(fp_line
			(start 2.54 3.81)
			(end 2.54 3.6703)
			(stroke
				(width 0.1524)
				(type default)
			)
			(layer "F.SilkS")
		)
		(fp_line
			(start 0 3.81)
			(end 2.54 3.81)
			(stroke
				(width 0.1524)
				(type default)
			)
			(layer "F.SilkS")
		)
		(fp_poly
			(pts
				(xy -0.761746 0) (xy -2.285746 -0.762) (xy -2.285746 0.762)
			)
			(stroke
				(width 0)
				(type default)
			)
			(fill yes)
			(layer "F.SilkS")
		)
		(fp_line
			(start 2.54 -1.27)
			(end 0 -1.27)
			(stroke
				(width 0.1)
				(type default)
			)
			(layer "F.Fab")
		)
		(fp_line
			(start 0 -1.27)
			(end 0 3.81)
			(stroke
				(width 0.1)
				(type default)
			)
			(layer "F.Fab")
		)
		(fp_line
			(start 2.54 3.81)
			(end 2.54 -1.27)
			(stroke
				(width 0.1)
				(type default)
			)
			(layer "F.Fab")
		)
		(fp_line
			(start 0 3.81)
			(end 2.54 3.81)
			(stroke
				(width 0.1)
				(type default)
			)
			(layer "F.Fab")
		)
		(fp_poly
			(pts
				(xy -0.761746 0) (xy -2.285746 -0.762) (xy -2.285746 0.762)
			)
			(stroke
				(width 0)
				(type default)
			)
			(fill yes)
			(layer "F.Fab")
		)
		(pad "1" thru_hole circle
			(at 0 0 90)
			(size 1.0033 1.0033)
			(drill 0.249936)
			(layers "*.Cu" "*.Mask")
			(remove_unused_layers no)
			(net "TDR_DIFF_85_BOT_DN")
			(clearance 0.10795)
			(thermal_gap 0.10795)
			(padstack
				(mode front_inner_back)
				(layer "Inner"
					(shape circle)
					(size 0.8001 0.8001)
					(clearance 0.1524)
				)
				(layer "B.Cu"
					(shape circle)
					(size 1.0033 1.0033)
					(clearance 0.10795)
				)
			)
		)
		(pad "2" thru_hole circle
			(at 2.54 0 90)
			(size 1.9939 1.9939)
			(drill 0.249936)
			(layers "*.Cu" "*.Mask")
			(remove_unused_layers no)
			(net "GND_P1")
			(clearance 0.10795)
			(thermal_gap 0.10795)
			(padstack
				(mode front_inner_back)
				(layer "Inner"
					(shape circle)
					(size 0.8001 0.8001)
					(clearance 0.1524)
				)
				(layer "B.Cu"
					(shape circle)
					(size 1.9939 1.9939)
					(clearance 0.10795)
				)
			)
		)
		(pad "3" thru_hole circle
			(at 2.54 2.54 90)
			(size 1.9939 1.9939)
			(drill 0.249936)
			(layers "*.Cu" "*.Mask")
			(remove_unused_layers no)
			(net "GND_P1")
			(clearance 0.10795)
			(thermal_gap 0.10795)
			(padstack
				(mode front_inner_back)
				(layer "Inner"
					(shape circle)
					(size 0.8001 0.8001)
					(clearance 0.1524)
				)
				(layer "B.Cu"
					(shape circle)
					(size 1.9939 1.9939)
					(clearance 0.10795)
				)
			)
		)
		(pad "4" thru_hole circle
			(at 0 2.54 90)
			(size 1.0033 1.0033)
			(drill 0.249936)
			(layers "*.Cu" "*.Mask")
			(remove_unused_layers no)
			(net "TDR_DIFF_85_BOT_DP")
			(clearance 0.10795)
			(thermal_gap 0.10795)
			(padstack
				(mode front_inner_back)
				(layer "Inner"
					(shape circle)
					(size 0.8001 0.8001)
					(clearance 0.1524)
				)
				(layer "B.Cu"
					(shape circle)
					(size 1.0033 1.0033)
					(clearance 0.10795)
				)
			)
		)
	)
	(footprint ""
		(layer "F.Cu")
		(at 40.10787 -38.881558 180)
		(property "Reference" "R173"
			(at 0 0 180)
			(layer "F.SilkS")
			(hide yes)
			(effects
				(font
					(size 1.27 1.27)
				)
			)
		)
		(property "Value" ""
			(at 0 0 180)
			(layer "F.Fab")
			(effects
				(font
					(size 1.27 1.27)
				)
			)
		)
		(duplicate_pad_numbers_are_jumpers no)
		(fp_line
			(start 0.7874 0.4064)
			(end -0.7874 0.4064)
			(stroke
				(width 0.1524)
				(type default)
			)
			(layer "F.SilkS")
		)
		(fp_line
			(start 0.7874 -0.4064)
			(end 0.7874 0.4064)
			(stroke
				(width 0.1524)
				(type default)
			)
			(layer "F.SilkS")
		)
		(fp_line
			(start -0.7874 0.4064)
			(end -0.7874 -0.4064)
			(stroke
				(width 0.1524)
				(type default)
			)
			(layer "F.SilkS")
		)
		(fp_line
			(start -0.7874 -0.4064)
			(end 0.7874 -0.4064)
			(stroke
				(width 0.1524)
				(type default)
			)
			(layer "F.SilkS")
		)
		(fp_line
			(start 0.67945 0.3048)
			(end 0.120396 0.3048)
			(stroke
				(width 0.1)
				(type default)
			)
			(layer "F.Fab")
		)
		(fp_line
			(start 0.67945 -0.3048)
			(end 0.67945 0.3048)
			(stroke
				(width 0.1)
				(type default)
			)
			(layer "F.Fab")
		)
		(fp_line
			(start 0.12065 -0.2794)
			(end 0.12065 -0.3048)
			(stroke
				(width 0.1)
				(type default)
			)
			(layer "F.Fab")
		)
		(fp_line
			(start 0.12065 -0.3048)
			(end 0.67945 -0.3048)
			(stroke
				(width 0.1)
				(type default)
			)
			(layer "F.Fab")
		)
		(fp_line
			(start 0.120396 0.3048)
			(end 0.120396 0.2794)
			(stroke
				(width 0.1)
				(type default)
			)
			(layer "F.Fab")
		)
		(fp_line
			(start 0.120396 0.2794)
			(end -0.12065 0.2794)
			(stroke
				(width 0.1)
				(type default)
			)
			(layer "F.Fab")
		)
		(fp_line
			(start -0.12065 0.3048)
			(end -0.67945 0.3048)
			(stroke
				(width 0.1)
				(type default)
			)
			(layer "F.Fab")
		)
		(fp_line
			(start -0.12065 0.2794)
			(end -0.12065 0.3048)
			(stroke
				(width 0.1)
				(type default)
			)
			(layer "F.Fab")
		)
		(fp_line
			(start -0.12065 -0.2794)
			(end 0.12065 -0.2794)
			(stroke
				(width 0.1)
				(type default)
			)
			(layer "F.Fab")
		)
		(fp_line
			(start -0.12065 -0.305054)
			(end -0.12065 -0.2794)
			(stroke
				(width 0.1)
				(type default)
			)
			(layer "F.Fab")
		)
		(fp_line
			(start -0.67945 0.3048)
			(end -0.67945 -0.305054)
			(stroke
				(width 0.1)
				(type default)
			)
			(layer "F.Fab")
		)
		(fp_line
			(start -0.67945 -0.305054)
			(end -0.12065 -0.305054)
			(stroke
				(width 0.1)
				(type default)
			)
			(layer "F.Fab")
		)
		(pad "1" smd circle
			(at -0.40005 0 180)
			(size 0 0)
			(layers "F.Cu" "F.Mask" "F.Paste")
			(net "RMII_TXD1_R")
		)
		(pad "2" smd circle
			(at 0.40005 0 180)
			(size 0 0)
			(layers "F.Cu" "F.Mask" "F.Paste")
			(net "RMII_TXD1")
		)
	)
)
